#ISCELL
  mstr_misc dns *
  *
#ISCELL
  pure_quanta quanta_title_block_c *
  *
#ISCELL
  pure_quanta_power cad_note *
  *
#ISCELL
  standard offpage *
  page323_i1
#ISCELL
  pure_quanta_power universal_power *
  page323_i10
#ISCELL
  standard offpage *
  page323_i11
#ISCELL
  pure_quanta_power gnd *
  page323_i12
#CELL
  pure_quanta q_cap *
  page323_i13
#ISCELL
  pure_quanta_power gnd *
  page323_i14
#CELL
  pure_quanta q_res *
  page323_i15
#ISCELL
  pure_quanta_power gnd *
  page323_i16
#CELL
  pure_quanta q_cap *
  page323_i17
#CELL
  pure_quanta q_res *
  page323_i18
#CELL
  pure_quanta q_res *
  page323_i19
#ISCELL
  pure_quanta_power universal_gnd *
  page323_i2
#ISCELL
  pure_quanta_power gnd *
  page323_i20
#ISCELL
  pure_quanta_power gnd *
  page323_i21
#CELL
  pure_quanta q_cap *
  page323_i22
#ISCELL
  pure_quanta_power gnd *
  page323_i23
#CELL
  pure_quanta q_cap *
  page323_i25
#ISCELL
  pure_quanta_power gnd *
  page323_i26
#ISCELL
  pure_quanta_power universal_power *
  page323_i27
#ISCELL
  pure_quanta_power universal_gnd *
  page323_i28
#ISCELL
  pure_quanta_power universal_gnd *
  page323_i29
#CELL
  pure_quanta q_cap *
  page323_i3
#CELL
  pure_quanta q_cap *
  page323_i30
#CELL
  pure_quanta mp5016gqhlz *
  page323_i31
#CELL
  pure_quanta q_cap *
  page323_i32
#ISCELL
  pure_quanta_power universal_gnd *
  page323_i33
#CELL
  pure_quanta q_cap *
  page323_i34
#ISCELL
  pure_quanta_power universal_power *
  page323_i35
#CELL
  pure_quanta q_res *
  page323_i36
#CELL
  pure_quanta q_res *
  page323_i37
#ISCELL
  pure_quanta_power gnd *
  page323_i38
#CELL
  pure_quanta q_cap *
  page323_i39
#CELL
  pure_quanta q_res *
  page323_i4
#CELL
  pure_quanta q_res *
  page323_i40
#ISCELL
  pure_quanta_power vccaux15 *
  page323_i41
#CELL
  pure_quanta q_res *
  page323_i42
#ISCELL
  standard offpage *
  page323_i43
#ISCELL
  standard offpage *
  page323_i44
#CELL
  pure_quanta q_res *
  page323_i45
#ISCELL
  pure_quanta_power vccaux15 *
  page323_i46
#CELL
  pure_quanta q_res *
  page323_i47
#CELL
  pure_quanta q_res *
  page323_i48
#CELL
  pure_quanta q_res *
  page323_i49
#CELL
  pure_quanta q_res *
  page323_i5
#ISCELL
  pure_quanta_power gnd *
  page323_i50
#CELL
  pure_quanta q_cap *
  page323_i51
#CELL
  pure_quanta q_res *
  page323_i52
#ISCELL
  pure_quanta_power universal_power *
  page323_i53
#CELL
  pure_quanta q_res *
  page323_i54
#ISCELL
  pure_quanta_power gnd *
  page323_i55
#CELL
  pure_quanta q_cap *
  page323_i56
#ISCELL
  pure_quanta_power universal_power *
  page323_i57
#ISCELL
  standard offpage *
  page323_i58
#ISCELL
  standard offpage *
  page323_i59
#CELL
  pure_quanta q_res *
  page323_i6
#ISCELL
  standard offpage *
  page323_i60
#ISCELL
  pure_quanta_power universal_gnd *
  page323_i63
#CELL
  pure_quanta q_cap *
  page323_i64
#CELL
  pure_quanta apx80929sag7 *
  page323_i65
#ISCELL
  pure_quanta_power universal_gnd *
  page323_i67
#CELL
  pure_quanta q_res *
  page323_i68
#ISCELL
  pure_quanta_power universal_gnd *
  page323_i69
#ISCELL
  pure_quanta_power universal_gnd *
  page323_i7
#CELL
  pure_quanta q_res *
  page323_i70
#CELL
  pure_quanta q_res *
  page323_i71
#ISCELL
  standard offpage *
  page323_i73
#ISCELL
  pure_quanta_power universal_power *
  page323_i74
#ISCELL
  pure_quanta_power universal_power *
  page323_i75
#CELL
  pure_quanta rs31312r *
  page323_i76
#ISCELL
  pure_quanta_power universal_gnd *
  page323_i8
#CELL
  pure_quanta q_cap *
  page323_i9
